(kicad_pcb
	(version 20260206)
	(generator "pcbnew")
	(generator_version "10.0")
	(general
		(thickness 1.6)
		(legacy_teardrops no)
	)
	(paper "A4")
	(title_block
		(title "01162023_DA0F0TEBIF0_F0T_Expander_BD_F_brd_V02_OCP.brd")
		(comment 1 "Grand Teton / footprints 3973-3979 of 9728")
	)
	(layers
		(0 "F.Cu" signal "TOP")
		(4 "In1.Cu" signal "GND")
		(6 "In2.Cu" signal "VCC")
		(8 "In3.Cu" signal "VCC1")
		(10 "In4.Cu" signal "GND1")
		(12 "In5.Cu" signal "IN1")
		(14 "In6.Cu" signal "GND2")
		(16 "In7.Cu" signal "IN2")
		(18 "In8.Cu" signal "GND3")
		(20 "In9.Cu" signal "IN3")
		(22 "In10.Cu" signal "GND4")
		(24 "In11.Cu" signal "IN4")
		(26 "In12.Cu" signal "GND5")
		(28 "In13.Cu" signal "IN5")
		(30 "In14.Cu" signal "GND6")
		(32 "In15.Cu" signal "IN6")
		(34 "In16.Cu" signal "GND7")
		(2 "B.Cu" signal "BOTTOM")
		(9 "F.Adhes" user "F.Adhesive")
		(11 "B.Adhes" user "B.Adhesive")
		(13 "F.Paste" user "Package Geometry/Pastemask Top")
		(15 "B.Paste" user "Package Geometry/Pastemask Bottom")
		(5 "F.SilkS" user "Ref Des/Silkscreen Top")
		(7 "B.SilkS" user "Ref Des/Silkscreen Bottom")
		(1 "F.Mask" user "Board Geometry/Soldermask Top")
		(3 "B.Mask" user "Board Geometry/Soldermask Bottom")
		(17 "Dwgs.User" user "User.Drawings")
		(19 "Cmts.User" user "User.Comments")
		(21 "Eco1.User" user "User.Eco1")
		(23 "Eco2.User" user "User.Eco2")
		(25 "Edge.Cuts" user "Board Geometry/Outline")
		(27 "Margin" user)
		(31 "F.CrtYd" user "Package Geometry/Place Bound Top")
		(29 "B.CrtYd" user "Package Geometry/Place Bound Bottom")
		(35 "F.Fab" user "Ref Des/Assembly Top")
		(33 "B.Fab" user "Ref Des/Assembly Bottom")
	)
	(footprint ""
		(layer "F.Cu")
		(at 363.474 -213.995 180)
		(property "Reference" "R4621"
			(at 0 0 180)
			(layer "F.SilkS")
			(hide yes)
			(effects
				(font
					(size 1.27 1.27)
				)
			)
		)
		(property "Value" ""
			(at 0 0 180)
			(layer "F.Fab")
			(effects
				(font
					(size 1.27 1.27)
				)
			)
		)
		(duplicate_pad_numbers_are_jumpers no)
		(fp_line
			(start 0.7874 0.4064)
			(end -0.7874 0.4064)
			(stroke
				(width 0.1524)
				(type default)
			)
			(layer "F.SilkS")
		)
		(fp_line
			(start 0.7874 -0.4064)
			(end 0.7874 0.4064)
			(stroke
				(width 0.1524)
				(type default)
			)
			(layer "F.SilkS")
		)
		(fp_line
			(start -0.7874 0.4064)
			(end -0.7874 -0.4064)
			(stroke
				(width 0.1524)
				(type default)
			)
			(layer "F.SilkS")
		)
		(fp_line
			(start -0.7874 -0.4064)
			(end 0.7874 -0.4064)
			(stroke
				(width 0.1524)
				(type default)
			)
			(layer "F.SilkS")
		)
		(fp_line
			(start 0.67945 0.3048)
			(end 0.120396 0.3048)
			(stroke
				(width 0.1)
				(type default)
			)
			(layer "F.Fab")
		)
		(fp_line
			(start 0.67945 -0.3048)
			(end 0.67945 0.3048)
			(stroke
				(width 0.1)
				(type default)
			)
			(layer "F.Fab")
		)
		(fp_line
			(start 0.12065 -0.2794)
			(end 0.12065 -0.3048)
			(stroke
				(width 0.1)
				(type default)
			)
			(layer "F.Fab")
		)
		(fp_line
			(start 0.12065 -0.3048)
			(end 0.67945 -0.3048)
			(stroke
				(width 0.1)
				(type default)
			)
			(layer "F.Fab")
		)
		(fp_line
			(start 0.120396 0.3048)
			(end 0.120396 0.2794)
			(stroke
				(width 0.1)
				(type default)
			)
			(layer "F.Fab")
		)
		(fp_line
			(start 0.120396 0.2794)
			(end -0.12065 0.2794)
			(stroke
				(width 0.1)
				(type default)
			)
			(layer "F.Fab")
		)
		(fp_line
			(start -0.12065 0.3048)
			(end -0.67945 0.3048)
			(stroke
				(width 0.1)
				(type default)
			)
			(layer "F.Fab")
		)
		(fp_line
			(start -0.12065 0.2794)
			(end -0.12065 0.3048)
			(stroke
				(width 0.1)
				(type default)
			)
			(layer "F.Fab")
		)
		(fp_line
			(start -0.12065 -0.2794)
			(end 0.12065 -0.2794)
			(stroke
				(width 0.1)
				(type default)
			)
			(layer "F.Fab")
		)
		(fp_line
			(start -0.12065 -0.305054)
			(end -0.12065 -0.2794)
			(stroke
				(width 0.1)
				(type default)
			)
			(layer "F.Fab")
		)
		(fp_line
			(start -0.67945 0.3048)
			(end -0.67945 -0.305054)
			(stroke
				(width 0.1)
				(type default)
			)
			(layer "F.Fab")
		)
		(fp_line
			(start -0.67945 -0.305054)
			(end -0.12065 -0.305054)
			(stroke
				(width 0.1)
				(type default)
			)
			(layer "F.Fab")
		)
		(pad "1" smd circle
			(at -0.40005 0 180)
			(size 0 0)
			(layers "F.Cu" "F.Mask" "F.Paste")
			(net "PCA9555_0_PEX0_A1")
		)
		(pad "2" smd circle
			(at 0.40005 0 180)
			(size 0 0)
			(layers "F.Cu" "F.Mask" "F.Paste")
			(net "P3V3_AUX")
		)
	)
	(footprint ""
		(layer "F.Cu")
		(at 314.861448 -147.99691 180)
		(property "Reference" "C432"
			(at 0 0 180)
			(layer "F.SilkS")
			(hide yes)
			(effects
				(font
					(size 1.27 1.27)
				)
			)
		)
		(property "Value" ""
			(at 0 0 180)
			(layer "F.Fab")
			(effects
				(font
					(size 1.27 1.27)
				)
			)
		)
		(duplicate_pad_numbers_are_jumpers no)
		(fp_line
			(start 0.299974 0.150114)
			(end -0.299974 0.150114)
			(stroke
				(width 0.1)
				(type default)
			)
			(layer "F.Fab")
		)
		(fp_line
			(start 0.299974 -0.150114)
			(end 0.299974 0.150114)
			(stroke
				(width 0.1)
				(type default)
			)
			(layer "F.Fab")
		)
		(fp_line
			(start -0.299974 0.150114)
			(end -0.299974 -0.150114)
			(stroke
				(width 0.1)
				(type default)
			)
			(layer "F.Fab")
		)
		(fp_line
			(start -0.299974 -0.150114)
			(end 0.299974 -0.150114)
			(stroke
				(width 0.1)
				(type default)
			)
			(layer "F.Fab")
		)
		(pad "1" smd rect
			(at -0.2667 0 180)
			(size 0.3048 0.381)
			(layers "F.Cu" "F.Mask" "F.Paste")
			(net "P5E_PEX2_STN0_TX_DN<11>")
		)
		(pad "2" smd rect
			(at 0.2667 0 180)
			(size 0.3048 0.381)
			(layers "F.Cu" "F.Mask" "F.Paste")
			(net "P5E_PEX2_STN0_TX_C_DN<11>")
		)
	)
	(footprint ""
		(layer "F.Cu")
		(at 5.75437 -48.21809)
		(property "Reference" "PD60"
			(at -1.636522 2.105914 0)
			(unlocked yes)
			(layer "F.SilkS")
			(effects
				(font
					(size 0.7874 0.5842)
					(thickness 0.1524)
				)
				(justify left)
			)
		)
		(property "Value" ""
			(at 0 0 0)
			(layer "F.Fab")
			(effects
				(font
					(size 1.27 1.27)
				)
			)
		)
		(duplicate_pad_numbers_are_jumpers no)
		(fp_line
			(start -3.400044 -1.459992)
			(end 4.107942 -1.459992)
			(stroke
				(width 0.1524)
				(type default)
			)
			(layer "F.SilkS")
		)
		(fp_line
			(start -3.400044 1.459992)
			(end -3.400044 -1.459992)
			(stroke
				(width 0.1524)
				(type default)
			)
			(layer "F.SilkS")
		)
		(fp_line
			(start 4.107942 -1.459992)
			(end 4.107942 1.459992)
			(stroke
				(width 0.1524)
				(type default)
			)
			(layer "F.SilkS")
		)
		(fp_line
			(start 4.107942 1.459992)
			(end -3.400044 1.459992)
			(stroke
				(width 0.1524)
				(type default)
			)
			(layer "F.SilkS")
		)
		(fp_poly
			(pts
				(xy 4.107942 -1.459992) (xy 4.107942 1.459992) (xy 3.308096 1.459992) (xy 3.308096 -1.459992)
			)
			(stroke
				(width 0)
				(type default)
			)
			(fill yes)
			(layer "F.SilkS")
		)
		(fp_line
			(start -2.29997 -1.459992)
			(end 2.29997 -1.459992)
			(stroke
				(width 0.1)
				(type default)
			)
			(layer "F.Fab")
		)
		(fp_line
			(start -2.29997 1.459992)
			(end -2.29997 -1.459992)
			(stroke
				(width 0.1)
				(type default)
			)
			(layer "F.Fab")
		)
		(fp_line
			(start 2.29997 -1.459992)
			(end 2.29997 1.459992)
			(stroke
				(width 0.1)
				(type default)
			)
			(layer "F.Fab")
		)
		(fp_line
			(start 2.29997 1.459992)
			(end -2.29997 1.459992)
			(stroke
				(width 0.1)
				(type default)
			)
			(layer "F.Fab")
		)
		(fp_text user "+"
			(at -4.7752 -0.12065 0)
			(unlocked yes)
			(layer "F.SilkS")
			(effects
				(font
					(size 1.905 1.4224)
					(thickness 0.1524)
				)
				(justify left)
			)
		)
		(fp_text user "-"
			(at 5.4102 0.29845 180)
			(unlocked yes)
			(layer "F.SilkS")
			(effects
				(font
					(size 1.905 1.4224)
					(thickness 0.1524)
				)
				(justify left)
			)
		)
		(fp_text user "+"
			(at -4.7752 -0.12065 0)
			(unlocked yes)
			(layer "F.Fab")
			(effects
				(font
					(size 1.905 1.4224)
					(thickness 0.1524)
				)
				(justify left)
			)
		)
		(fp_text user "-"
			(at 5.4102 0.29845 180)
			(unlocked yes)
			(layer "F.Fab")
			(effects
				(font
					(size 1.905 1.4224)
					(thickness 0.1524)
				)
				(justify left)
			)
		)
		(pad "A" smd rect
			(at -1.999996 0 90)
			(size 1.7018 2.5146)
			(layers "F.Cu" "F.Mask" "F.Paste")
			(net "GND")
		)
		(pad "C" smd rect
			(at 1.999996 0 90)
			(size 1.7018 2.5146)
			(layers "F.Cu" "F.Mask" "F.Paste")
			(net "P3V3_SSD0")
		)
	)
	(footprint ""
		(layer "F.Cu")
		(at 215.047322 -21.37156)
		(property "Reference" "C3925"
			(at 0 0 0)
			(layer "F.SilkS")
			(hide yes)
			(effects
				(font
					(size 1.27 1.27)
				)
			)
		)
		(property "Value" ""
			(at 0 0 0)
			(layer "F.Fab")
			(effects
				(font
					(size 1.27 1.27)
				)
			)
		)
		(duplicate_pad_numbers_are_jumpers no)
		(fp_line
			(start -0.7874 -0.4064)
			(end 0.7874 -0.4064)
			(stroke
				(width 0.1524)
				(type default)
			)
			(layer "F.SilkS")
		)
		(fp_line
			(start -0.7874 0.4064)
			(end -0.7874 -0.4064)
			(stroke
				(width 0.1524)
				(type default)
			)
			(layer "F.SilkS")
		)
		(fp_line
			(start 0.7874 -0.4064)
			(end 0.7874 0.4064)
			(stroke
				(width 0.1524)
				(type default)
			)
			(layer "F.SilkS")
		)
		(fp_line
			(start 0.7874 0.4064)
			(end -0.7874 0.4064)
			(stroke
				(width 0.1524)
				(type default)
			)
			(layer "F.SilkS")
		)
		(fp_line
			(start -0.67945 -0.305054)
			(end -0.12065 -0.305054)
			(stroke
				(width 0.1)
				(type default)
			)
			(layer "F.Fab")
		)
		(fp_line
			(start -0.67945 0.3048)
			(end -0.67945 -0.305054)
			(stroke
				(width 0.1)
				(type default)
			)
			(layer "F.Fab")
		)
		(fp_line
			(start -0.12065 -0.305054)
			(end -0.12065 -0.2794)
			(stroke
				(width 0.1)
				(type default)
			)
			(layer "F.Fab")
		)
		(fp_line
			(start -0.12065 -0.2794)
			(end 0.12065 -0.2794)
			(stroke
				(width 0.1)
				(type default)
			)
			(layer "F.Fab")
		)
		(fp_line
			(start -0.12065 0.2794)
			(end -0.12065 0.3048)
			(stroke
				(width 0.1)
				(type default)
			)
			(layer "F.Fab")
		)
		(fp_line
			(start -0.12065 0.3048)
			(end -0.67945 0.3048)
			(stroke
				(width 0.1)
				(type default)
			)
			(layer "F.Fab")
		)
		(fp_line
			(start 0.120396 0.2794)
			(end -0.12065 0.2794)
			(stroke
				(width 0.1)
				(type default)
			)
			(layer "F.Fab")
		)
		(fp_line
			(start 0.120396 0.3048)
			(end 0.120396 0.2794)
			(stroke
				(width 0.1)
				(type default)
			)
			(layer "F.Fab")
		)
		(fp_line
			(start 0.12065 -0.3048)
			(end 0.67945 -0.3048)
			(stroke
				(width 0.1)
				(type default)
			)
			(layer "F.Fab")
		)
		(fp_line
			(start 0.12065 -0.2794)
			(end 0.12065 -0.3048)
			(stroke
				(width 0.1)
				(type default)
			)
			(layer "F.Fab")
		)
		(fp_line
			(start 0.67945 -0.3048)
			(end 0.67945 0.3048)
			(stroke
				(width 0.1)
				(type default)
			)
			(layer "F.Fab")
		)
		(fp_line
			(start 0.67945 0.3048)
			(end 0.120396 0.3048)
			(stroke
				(width 0.1)
				(type default)
			)
			(layer "F.Fab")
		)
		(pad "1" smd circle
			(at -0.40005 0)
			(size 0 0)
			(layers "F.Cu" "F.Mask" "F.Paste")
			(net "P12V_SSD7")
		)
		(pad "2" smd circle
			(at 0.40005 0)
			(size 0 0)
			(layers "F.Cu" "F.Mask" "F.Paste")
			(net "GND")
		)
	)
	(footprint ""
		(layer "F.Cu")
		(at 174.129192 -205.903576)
		(property "Reference" "ME2"
			(at 0 0 0)
			(layer "F.SilkS")
			(hide yes)
			(effects
				(font
					(size 1.27 1.27)
				)
			)
		)
		(property "Value" ""
			(at 0 0 0)
			(layer "F.Fab")
			(effects
				(font
					(size 1.27 1.27)
				)
			)
		)
		(duplicate_pad_numbers_are_jumpers no)
		(fp_poly
			(pts
				(xy 0 -0.5842) (xy 3.3401 -0.5842) (xy 3.3401 0) (xy 0 0)
			)
			(stroke
				(width 0)
				(type default)
			)
			(fill yes)
			(layer "F.SilkS")
		)
		(fp_poly
			(pts
				(xy 1.32715 -3.4417) (xy 2.01295 -3.4417) (xy 2.01295 -3.2512) (xy 1.32715 -3.2512)
			)
			(stroke
				(width 0)
				(type default)
			)
			(fill yes)
			(layer "F.SilkS")
		)
		(fp_poly
			(pts
				(xy -0.070612 -0.681228) (xy -0.197612 -0.820928) (xy 0.852678 -1.91262) (xy 0.728472 -3.29184)
				(xy -0.248412 -4.300728) (xy -0.184912 -4.478528) (xy -0.007112 -4.503928) (xy 0.684022 -3.785616)
				(xy 0.65659 -4.0894) (xy 0.97155 -4.3434) (xy 1.22555 -4.3561) (xy 1.46685 -4.4704) (xy 2.01295 -4.4704)
				(xy 2.15265 -4.4069) (xy 2.44475 -4.191) (xy 2.49555 -4.191) (xy 2.59715 -4.2926) (xy 2.80035 -4.2672)
				(xy 2.88925 -4.1656) (xy 2.88925 -4.029456) (xy 3.345688 -4.503928) (xy 3.523488 -4.478528) (xy 3.586988 -4.300728)
				(xy 2.88925 -3.58013) (xy 2.88925 -3.3147) (xy 2.82575 -3.2385) (xy 2.67335 -3.2385) (xy 2.521966 -1.875282)
				(xy 2.545842 -1.85039)
				(arc
					(start 2.55905 -1.8415)
					(mid 2.648099 -1.766068)
					(end 2.717292 -1.672082)
				)
				(xy 3.536188 -0.820928) (xy 3.409188 -0.681228) (xy 3.244088 -0.693928)
				(arc
					(start 2.737612 -1.216914)
					(mid 2.31728 -0.925553)
					(end 1.86055 -1.1557)
				)
				(xy 0.92075 -1.1557) (xy 0.888492 -1.51384) (xy 0.094488 -0.693928)
			)
			(stroke
				(width 0)
				(type default)
			)
			(fill yes)
			(layer "F.SilkS")
		)
	)
	(footprint ""
		(layer "F.Cu")
		(at 219.202 -198.628)
		(property "Reference" "R1522"
			(at 0 0 0)
			(layer "F.SilkS")
			(hide yes)
			(effects
				(font
					(size 1.27 1.27)
				)
			)
		)
		(property "Value" ""
			(at 0 0 0)
			(layer "F.Fab")
			(effects
				(font
					(size 1.27 1.27)
				)
			)
		)
		(duplicate_pad_numbers_are_jumpers no)
		(fp_line
			(start -0.7874 -0.4064)
			(end 0.7874 -0.4064)
			(stroke
				(width 0.1524)
				(type default)
			)
			(layer "F.SilkS")
		)
		(fp_line
			(start -0.7874 0.4064)
			(end -0.7874 -0.4064)
			(stroke
				(width 0.1524)
				(type default)
			)
			(layer "F.SilkS")
		)
		(fp_line
			(start 0.7874 -0.4064)
			(end 0.7874 0.4064)
			(stroke
				(width 0.1524)
				(type default)
			)
			(layer "F.SilkS")
		)
		(fp_line
			(start 0.7874 0.4064)
			(end -0.7874 0.4064)
			(stroke
				(width 0.1524)
				(type default)
			)
			(layer "F.SilkS")
		)
		(fp_line
			(start -0.67945 -0.305054)
			(end -0.12065 -0.305054)
			(stroke
				(width 0.1)
				(type default)
			)
			(layer "F.Fab")
		)
		(fp_line
			(start -0.67945 0.3048)
			(end -0.67945 -0.305054)
			(stroke
				(width 0.1)
				(type default)
			)
			(layer "F.Fab")
		)
		(fp_line
			(start -0.12065 -0.305054)
			(end -0.12065 -0.2794)
			(stroke
				(width 0.1)
				(type default)
			)
			(layer "F.Fab")
		)
		(fp_line
			(start -0.12065 -0.2794)
			(end 0.12065 -0.2794)
			(stroke
				(width 0.1)
				(type default)
			)
			(layer "F.Fab")
		)
		(fp_line
			(start -0.12065 0.2794)
			(end -0.12065 0.3048)
			(stroke
				(width 0.1)
				(type default)
			)
			(layer "F.Fab")
		)
		(fp_line
			(start -0.12065 0.3048)
			(end -0.67945 0.3048)
			(stroke
				(width 0.1)
				(type default)
			)
			(layer "F.Fab")
		)
		(fp_line
			(start 0.120396 0.2794)
			(end -0.12065 0.2794)
			(stroke
				(width 0.1)
				(type default)
			)
			(layer "F.Fab")
		)
		(fp_line
			(start 0.120396 0.3048)
			(end 0.120396 0.2794)
			(stroke
				(width 0.1)
				(type default)
			)
			(layer "F.Fab")
		)
		(fp_line
			(start 0.12065 -0.3048)
			(end 0.67945 -0.3048)
			(stroke
				(width 0.1)
				(type default)
			)
			(layer "F.Fab")
		)
		(fp_line
			(start 0.12065 -0.2794)
			(end 0.12065 -0.3048)
			(stroke
				(width 0.1)
				(type default)
			)
			(layer "F.Fab")
		)
		(fp_line
			(start 0.67945 -0.3048)
			(end 0.67945 0.3048)
			(stroke
				(width 0.1)
				(type default)
			)
			(layer "F.Fab")
		)
		(fp_line
			(start 0.67945 0.3048)
			(end 0.120396 0.3048)
			(stroke
				(width 0.1)
				(type default)
			)
			(layer "F.Fab")
		)
		(pad "1" smd circle
			(at -0.40005 0)
			(size 0 0)
			(layers "F.Cu" "F.Mask" "F.Paste")
			(net "SMB_NIC6_LS_R_SDA")
		)
		(pad "2" smd circle
			(at 0.40005 0)
			(size 0 0)
			(layers "F.Cu" "F.Mask" "F.Paste")
			(net "P3V3_NIC6")
		)
	)
	(footprint ""
		(layer "F.Cu")
		(at 375.426224 -39.73576 -90)
		(property "Reference" "R5572"
			(at 0 0 270)
			(layer "F.SilkS")
			(hide yes)
			(effects
				(font
					(size 1.27 1.27)
				)
			)
		)
		(property "Value" ""
			(at 0 0 270)
			(layer "F.Fab")
			(effects
				(font
					(size 1.27 1.27)
				)
			)
		)
		(duplicate_pad_numbers_are_jumpers no)
		(fp_line
			(start -0.7874 0.4064)
			(end -0.7874 -0.4064)
			(stroke
				(width 0.1524)
				(type default)
			)
			(layer "F.SilkS")
		)
		(fp_line
			(start 0.7874 0.4064)
			(end -0.7874 0.4064)
			(stroke
				(width 0.1524)
				(type default)
			)
			(layer "F.SilkS")
		)
		(fp_line
			(start -0.7874 -0.4064)
			(end 0.7874 -0.4064)
			(stroke
				(width 0.1524)
				(type default)
			)
			(layer "F.SilkS")
		)
		(fp_line
			(start 0.7874 -0.4064)
			(end 0.7874 0.4064)
			(stroke
				(width 0.1524)
				(type default)
			)
			(layer "F.SilkS")
		)
		(fp_line
			(start -0.67945 0.3048)
			(end -0.67945 -0.305054)
			(stroke
				(width 0.1)
				(type default)
			)
			(layer "F.Fab")
		)
		(fp_line
			(start -0.12065 0.3048)
			(end -0.67945 0.3048)
			(stroke
				(width 0.1)
				(type default)
			)
			(layer "F.Fab")
		)
		(fp_line
			(start 0.120396 0.3048)
			(end 0.120396 0.2794)
			(stroke
				(width 0.1)
				(type default)
			)
			(layer "F.Fab")
		)
		(fp_line
			(start 0.67945 0.3048)
			(end 0.120396 0.3048)
			(stroke
				(width 0.1)
				(type default)
			)
			(layer "F.Fab")
		)
		(fp_line
			(start -0.12065 0.2794)
			(end -0.12065 0.3048)
			(stroke
				(width 0.1)
				(type default)
			)
			(layer "F.Fab")
		)
		(fp_line
			(start 0.120396 0.2794)
			(end -0.12065 0.2794)
			(stroke
				(width 0.1)
				(type default)
			)
			(layer "F.Fab")
		)
		(fp_line
			(start -0.12065 -0.2794)
			(end 0.12065 -0.2794)
			(stroke
				(width 0.1)
				(type default)
			)
			(layer "F.Fab")
		)
		(fp_line
			(start 0.12065 -0.2794)
			(end 0.12065 -0.3048)
			(stroke
				(width 0.1)
				(type default)
			)
			(layer "F.Fab")
		)
		(fp_line
			(start 0.12065 -0.3048)
			(end 0.67945 -0.3048)
			(stroke
				(width 0.1)
				(type default)
			)
			(layer "F.Fab")
		)
		(fp_line
			(start 0.67945 -0.3048)
			(end 0.67945 0.3048)
			(stroke
				(width 0.1)
				(type default)
			)
			(layer "F.Fab")
		)
		(fp_line
			(start -0.67945 -0.305054)
			(end -0.12065 -0.305054)
			(stroke
				(width 0.1)
				(type default)
			)
			(layer "F.Fab")
		)
		(fp_line
			(start -0.12065 -0.305054)
			(end -0.12065 -0.2794)
			(stroke
				(width 0.1)
				(type default)
			)
			(layer "F.Fab")
		)
		(pad "1" smd circle
			(at -0.40005 0 270)
			(size 0 0)
			(layers "F.Cu" "F.Mask" "F.Paste")
			(net "P3V3_AUX")
		)
		(pad "2" smd circle
			(at 0.40005 0 270)
			(size 0 0)
			(layers "F.Cu" "F.Mask" "F.Paste")
			(net "SSD13_AUX_P3V3_EN")
		)
	)
)
